(kicad_pcb
	(version 20241229)
	(generator "pcbnew")
	(generator_version "9.0")
	(general
		(thickness 1.63)
		(legacy_teardrops no)
	)
	(paper "A4")
	(title_block
		(title "CM4 Baseboard")
		(date "2026-01-05")
		(rev "1.1.1")
		(company "Antmicro Ltd")
		(comment 1 "www.antmicro.com")
		(comment 9 "footprints 422-426 of 506")
	)
	(layers
		(0 "F.Cu" signal)
		(4 "In1.Cu" power)
		(6 "In2.Cu" power)
		(8 "In3.Cu" signal)
		(10 "In4.Cu" signal)
		(2 "B.Cu" signal)
		(9 "F.Adhes" user "F.Adhesive")
		(11 "B.Adhes" user "B.Adhesive")
		(13 "F.Paste" user)
		(15 "B.Paste" user)
		(5 "F.SilkS" user "F.Silkscreen")
		(7 "B.SilkS" user "B.Silkscreen")
		(1 "F.Mask" user)
		(3 "B.Mask" user)
		(17 "Dwgs.User" user "User.Drawings")
		(19 "Cmts.User" user "User.Comments")
		(21 "Eco1.User" user "User.Eco1")
		(23 "Eco2.User" user "User.Eco2")
		(25 "Edge.Cuts" user)
		(27 "Margin" user)
		(31 "F.CrtYd" user "F.Courtyard")
		(29 "B.CrtYd" user "B.Courtyard")
		(35 "F.Fab" user)
		(33 "B.Fab" user)
	)
	(footprint "antmicro-footprints:R_0402_1005Metric"
		(layer "B.Cu")
		(at 62.117962 136.1165)
		(descr "Resistor SMD 0402")
		(tags "resistor SMD 0402")
		(property "Reference" "R421"
			(at -1.16 1.39 0)
			(layer "B.SilkS")
			(effects
				(font
					(size 0.7 0.7)
					(thickness 0.15)
				)
				(justify right bottom mirror)
			)
		)
		(property "Value" "R_470R_0402"
			(at -1.011843 -1.772047 0)
			(layer "B.Fab")
			(effects
				(font
					(size 0.7 0.7)
					(thickness 0.15)
				)
				(justify right bottom mirror)
			)
		)
		(property "Datasheet" "https://www.bourns.com/docs/product-datasheets/cr.pdf"
			(at 0 0 0)
			(layer "B.Fab")
			(hide yes)
			(effects
				(font
					(size 1.27 1.27)
					(thickness 0.15)
				)
			)
		)
		(property "Manufacturer" "Bourns"
			(at 0 0 0)
			(unlocked yes)
			(layer "B.Fab")
			(hide yes)
			(effects
				(font
					(size 1 1)
					(thickness 0.15)
				)
				(justify mirror)
			)
		)
		(property "MPN" "CR0402-FX-4700GLF"
			(at 0 0 0)
			(unlocked yes)
			(layer "B.Fab")
			(hide yes)
			(effects
				(font
					(size 1 1)
					(thickness 0.15)
				)
				(justify mirror)
			)
		)
		(property "Val" "470R"
			(at 0 0 0)
			(unlocked yes)
			(layer "B.Fab")
			(hide yes)
			(effects
				(font
					(size 1 1)
					(thickness 0.15)
				)
				(justify mirror)
			)
		)
		(property "License" "Apache-2.0"
			(at 0 0 0)
			(unlocked yes)
			(layer "B.Fab")
			(hide yes)
			(effects
				(font
					(size 1 1)
					(thickness 0.15)
				)
				(justify mirror)
			)
		)
		(property "Author" "Antmicro"
			(at 0 0 0)
			(unlocked yes)
			(layer "B.Fab")
			(hide yes)
			(effects
				(font
					(size 1 1)
					(thickness 0.15)
				)
				(justify mirror)
			)
		)
		(property "Tolerance" "1%"
			(at 0 0 0)
			(unlocked yes)
			(layer "B.Fab")
			(hide yes)
			(effects
				(font
					(size 1 1)
					(thickness 0.15)
				)
				(justify mirror)
			)
		)
		(sheetname "/Ethernet/")
		(sheetfile "ethernet.kicad_sch")
		(attr smd)
		(fp_rect
			(start -0.925 0.47)
			(end 0.925 -0.47)
			(stroke
				(width 0.05)
				(type default)
			)
			(fill no)
			(layer "B.CrtYd")
		)
		(fp_rect
			(start -0.5 0.25)
			(end 0.5 -0.25)
			(stroke
				(width 0.15)
				(type solid)
			)
			(fill no)
			(layer "B.Fab")
		)
		(fp_text user "${REFERENCE}"
			(at -0.95 -3.168 180)
			(layer "B.Fab")
			(effects
				(font
					(size 0.7 0.7)
					(thickness 0.15)
				)
				(justify left bottom mirror)
			)
		)
		(fp_text user "Author: Antmicro"
			(at -0.95 -4.169 180)
			(layer "B.Fab")
			(effects
				(font
					(size 0.7 0.7)
					(thickness 0.15)
				)
				(justify left bottom mirror)
			)
		)
		(fp_text user "License: Apache-2.0"
			(at -0.95 -5.169 180)
			(layer "B.Fab")
			(effects
				(font
					(size 0.7 0.7)
					(thickness 0.15)
				)
				(justify left bottom mirror)
			)
		)
		(pad "1" smd roundrect
			(at -0.48 0)
			(size 0.59 0.64)
			(layers "B.Cu" "B.Mask" "B.Paste")
			(roundrect_rratio 0.25)
			(net 367 "Net-(R421-Pad1)")
			(pintype "passive")
		)
		(pad "2" smd roundrect
			(at 0.48 0)
			(size 0.59 0.64)
			(layers "B.Cu" "B.Mask" "B.Paste")
			(roundrect_rratio 0.25)
			(net 3 "GND")
			(pintype "passive")
		)
	)
	(footprint "antmicro-footprints:SOT-363"
		(layer "B.Cu")
		(at 52.992962 163.6145)
		(property "Reference" "Q303"
			(at 2.125038 1.777 90)
			(layer "B.SilkS")
			(effects
				(font
					(size 0.7 0.7)
					(thickness 0.15)
				)
				(justify right bottom mirror)
			)
		)
		(property "Value" "DZDH0401DW"
			(at 0 -2.2 0)
			(layer "B.Fab")
			(effects
				(font
					(size 0.7 0.7)
					(thickness 0.15)
				)
				(justify right bottom mirror)
			)
		)
		(property "Datasheet" "https://www.mouser.com/datasheet/2/115/DIOD_S_A0011803041_1-2543705.pdf"
			(at 0 0 0)
			(layer "B.Fab")
			(hide yes)
			(effects
				(font
					(size 1.27 1.27)
					(thickness 0.15)
				)
			)
		)
		(property "MPN" "DZDH0401DW"
			(at 0 0 0)
			(unlocked yes)
			(layer "B.Fab")
			(hide yes)
			(effects
				(font
					(size 1 1)
					(thickness 0.15)
				)
				(justify mirror)
			)
		)
		(property "Manufacturer" "Diodes Incorporated"
			(at 0 0 0)
			(unlocked yes)
			(layer "B.Fab")
			(hide yes)
			(effects
				(font
					(size 1 1)
					(thickness 0.15)
				)
				(justify mirror)
			)
		)
		(property "Author" "Antmicro"
			(at 0 0 0)
			(unlocked yes)
			(layer "B.Fab")
			(hide yes)
			(effects
				(font
					(size 1 1)
					(thickness 0.15)
				)
				(justify mirror)
			)
		)
		(property "License" "Apache-2.0"
			(at 0 0 0)
			(unlocked yes)
			(layer "B.Fab")
			(hide yes)
			(effects
				(font
					(size 1 1)
					(thickness 0.15)
				)
				(justify mirror)
			)
		)
		(sheetname "/Supply/")
		(sheetfile "supply.kicad_sch")
		(attr smd)
		(fp_line
			(start -0.8 -1.223)
			(end 0.803 -1.223)
			(stroke
				(width 0.15)
				(type solid)
			)
			(layer "B.SilkS")
		)
		(fp_line
			(start -0.8 -1.146)
			(end -0.8 -1.223)
			(stroke
				(width 0.15)
				(type solid)
			)
			(layer "B.SilkS")
		)
		(fp_line
			(start -0.72 1.153)
			(end -0.72 1.228)
			(stroke
				(width 0.15)
				(type solid)
			)
			(layer "B.SilkS")
		)
		(fp_line
			(start 0.803 -1.146)
			(end 0.803 -1.223)
			(stroke
				(width 0.15)
				(type solid)
			)
			(layer "B.SilkS")
		)
		(fp_line
			(start 0.803 1.153)
			(end 0.803 1.228)
			(stroke
				(width 0.15)
				(type solid)
			)
			(layer "B.SilkS")
		)
		(fp_line
			(start 0.803 1.228)
			(end -0.72 1.228)
			(stroke
				(width 0.15)
				(type solid)
			)
			(layer "B.SilkS")
		)
		(fp_circle
			(center -0.978102 1.2)
			(end -0.928102 1.2)
			(stroke
				(width 0.15)
				(type solid)
			)
			(fill yes)
			(layer "B.SilkS")
		)
		(fp_rect
			(start 1.3 1.3)
			(end -1.3 -1.3)
			(stroke
				(width 0.05)
				(type solid)
			)
			(fill no)
			(layer "B.CrtYd")
		)
		(fp_line
			(start -0.1 1.1)
			(end -0.68 0.52)
			(stroke
				(width 0.15)
				(type solid)
			)
			(layer "B.Fab")
		)
		(fp_rect
			(start 0.68 -1.1)
			(end -0.68 1.1)
			(stroke
				(width 0.15)
				(type solid)
			)
			(fill no)
			(layer "B.Fab")
		)
		(fp_text user "Author: Antmicro"
			(at -1.3 -6.4 180)
			(layer "B.Fab")
			(effects
				(font
					(size 0.7 0.7)
					(thickness 0.15)
				)
				(justify left bottom mirror)
			)
		)
		(fp_text user "License: Apache-2.0"
			(at -1.3 -5.2 180)
			(layer "B.Fab")
			(effects
				(font
					(size 0.7 0.7)
					(thickness 0.15)
				)
				(justify left bottom mirror)
			)
		)
		(fp_text user "${REFERENCE}"
			(at -1.3 -4 180)
			(layer "B.Fab")
			(effects
				(font
					(size 0.7 0.7)
					(thickness 0.15)
				)
				(justify left bottom mirror)
			)
		)
		(pad "1" smd custom
			(at -0.948 0.752 90)
			(size 0.6 0.6)
			(layers "B.Cu" "B.Mask" "B.Paste")
			(net 496 "unconnected-(Q303-NC-Pad1)")
			(pinfunction "NC")
			(pintype "no_connect")
			(options
				(clearance outline)
				(anchor rect)
			)
			(primitives)
		)
		(pad "2" smd rect
			(at -0.948 0.002 90)
			(size 0.4 0.6)
			(layers "B.Cu" "B.Mask" "B.Paste")
			(net 336 "Net-(Q303-REF)")
			(pinfunction "REF")
			(pintype "input")
		)
		(pad "3" smd custom
			(at -0.948 -0.745 90)
			(size 0.6 0.6)
			(layers "B.Cu" "B.Mask" "B.Paste")
			(net 337 "Net-(Q303-BIAS)")
			(pinfunction "BIAS")
			(pintype "output")
			(options
				(clearance outline)
				(anchor rect)
			)
			(primitives)
		)
		(pad "4" smd custom
			(at 0.951 -0.745 90)
			(size 0.6 0.6)
			(layers "B.Cu" "B.Mask" "B.Paste")
			(net 21 "/Supply/VCC_IN")
			(pinfunction "S")
			(pintype "power_in")
			(options
				(clearance outline)
				(anchor rect)
			)
			(primitives)
		)
		(pad "5" smd rect
			(at 0.951 0.002 90)
			(size 0.4 0.6)
			(layers "B.Cu" "B.Mask" "B.Paste")
			(net 497 "unconnected-(Q303-NC-Pad5)")
			(pinfunction "NC")
			(pintype "no_connect")
		)
		(pad "6" smd custom
			(at 0.951 0.752 90)
			(size 0.6 0.6)
			(layers "B.Cu" "B.Mask" "B.Paste")
			(net 443 "/Supply/V_{BUS}")
			(pinfunction "D")
			(pintype "power_in")
			(options
				(clearance outline)
				(anchor rect)
			)
			(primitives)
		)
	)
	(footprint "antmicro-footprints:R_0402_1005Metric"
		(layer "B.Cu")
		(at 92.537962 154.3665)
		(descr "Resistor SMD 0402")
		(tags "resistor SMD 0402")
		(property "Reference" "R230"
			(at -0.99 3.96 0)
			(layer "B.SilkS")
			(effects
				(font
					(size 0.7 0.7)
					(thickness 0.15)
				)
				(justify right bottom mirror)
			)
		)
		(property "Value" "R_10k_0402"
			(at -1.011843 -1.772047 0)
			(layer "B.Fab")
			(effects
				(font
					(size 0.7 0.7)
					(thickness 0.15)
				)
				(justify right bottom mirror)
			)
		)
		(property "Datasheet" "https://www.bourns.com/docs/product-datasheets/cr.pdf"
			(at 0 0 0)
			(layer "B.Fab")
			(hide yes)
			(effects
				(font
					(size 1.27 1.27)
					(thickness 0.15)
				)
			)
		)
		(property "MPN" "CR0402-FX-1002GLF"
			(at 0 0 0)
			(unlocked yes)
			(layer "B.Fab")
			(hide yes)
			(effects
				(font
					(size 1 1)
					(thickness 0.15)
				)
				(justify mirror)
			)
		)
		(property "Manufacturer" "Bourns"
			(at 0 0 0)
			(unlocked yes)
			(layer "B.Fab")
			(hide yes)
			(effects
				(font
					(size 1 1)
					(thickness 0.15)
				)
				(justify mirror)
			)
		)
		(property "License" "Apache-2.0"
			(at 0 0 0)
			(unlocked yes)
			(layer "B.Fab")
			(hide yes)
			(effects
				(font
					(size 1 1)
					(thickness 0.15)
				)
				(justify mirror)
			)
		)
		(property "Author" "Antmicro"
			(at 0 0 0)
			(unlocked yes)
			(layer "B.Fab")
			(hide yes)
			(effects
				(font
					(size 1 1)
					(thickness 0.15)
				)
				(justify mirror)
			)
		)
		(property "Val" "10k"
			(at 0 0 0)
			(unlocked yes)
			(layer "B.Fab")
			(hide yes)
			(effects
				(font
					(size 1 1)
					(thickness 0.15)
				)
				(justify mirror)
			)
		)
		(property "Tolerance" "1%"
			(at 0 0 0)
			(unlocked yes)
			(layer "B.Fab")
			(hide yes)
			(effects
				(font
					(size 1 1)
					(thickness 0.15)
				)
				(justify mirror)
			)
		)
		(sheetname "/Compute module/")
		(sheetfile "compute-module.kicad_sch")
		(attr smd exclude_from_pos_files exclude_from_bom dnp)
		(fp_rect
			(start -0.925 0.47)
			(end 0.925 -0.47)
			(stroke
				(width 0.05)
				(type default)
			)
			(fill no)
			(layer "B.CrtYd")
		)
		(fp_rect
			(start -0.5 0.25)
			(end 0.5 -0.25)
			(stroke
				(width 0.15)
				(type solid)
			)
			(fill no)
			(layer "B.Fab")
		)
		(fp_text user "License: Apache-2.0"
			(at -0.95 -5.169 180)
			(layer "B.Fab")
			(effects
				(font
					(size 0.7 0.7)
					(thickness 0.15)
				)
				(justify left bottom mirror)
			)
		)
		(fp_text user "${REFERENCE}"
			(at -0.95 -3.168 180)
			(layer "B.Fab")
			(effects
				(font
					(size 0.7 0.7)
					(thickness 0.15)
				)
				(justify left bottom mirror)
			)
		)
		(fp_text user "Author: Antmicro"
			(at -0.95 -4.169 180)
			(layer "B.Fab")
			(effects
				(font
					(size 0.7 0.7)
					(thickness 0.15)
				)
				(justify left bottom mirror)
			)
		)
		(pad "1" smd roundrect
			(at -0.48 0)
			(size 0.59 0.64)
			(layers "B.Cu" "B.Mask" "B.Paste")
			(roundrect_rratio 0.25)
			(net 345 "Net-(U204-A2)")
			(pintype "passive")
		)
		(pad "2" smd roundrect
			(at 0.48 0)
			(size 0.59 0.64)
			(layers "B.Cu" "B.Mask" "B.Paste")
			(roundrect_rratio 0.25)
			(net 9 "+3V3")
			(pintype "passive")
		)
	)
	(footprint "antmicro-footprints:C_0805_2012Metric"
		(layer "B.Cu")
		(at 89.627962 130.7365 180)
		(descr "Capacitor SMD 0805")
		(tags "capacitor SMD 0805")
		(property "Reference" "C911"
			(at -1.85 -2.76 0)
			(layer "B.SilkS")
			(effects
				(font
					(size 0.7 0.7)
					(thickness 0.15)
				)
				(justify left bottom mirror)
			)
		)
		(property "Value" "C_22u_25V_0805"
			(at -2.055717 -1.963152 0)
			(layer "B.Fab")
			(effects
				(font
					(size 0.7 0.7)
					(thickness 0.15)
				)
				(justify left bottom mirror)
			)
		)
		(property "Datasheet" "https://product.samsungsem.com/mlcc/CL21A226MAYNNN.do"
			(at 0 0 180)
			(layer "B.Fab")
			(hide yes)
			(effects
				(font
					(size 1.27 1.27)
					(thickness 0.15)
				)
			)
		)
		(property "Manufacturer" "Samsung Electro-Mechanics"
			(at 0 0 180)
			(unlocked yes)
			(layer "B.Fab")
			(hide yes)
			(effects
				(font
					(size 1 1)
					(thickness 0.15)
				)
				(justify mirror)
			)
		)
		(property "MPN" "CL21A226MAYNNNE"
			(at 0 0 180)
			(unlocked yes)
			(layer "B.Fab")
			(hide yes)
			(effects
				(font
					(size 1 1)
					(thickness 0.15)
				)
				(justify mirror)
			)
		)
		(property "Val" "22u"
			(at 0 0 180)
			(unlocked yes)
			(layer "B.Fab")
			(hide yes)
			(effects
				(font
					(size 1 1)
					(thickness 0.15)
				)
				(justify mirror)
			)
		)
		(property "License" "Apache-2.0"
			(at 0 0 180)
			(unlocked yes)
			(layer "B.Fab")
			(hide yes)
			(effects
				(font
					(size 1 1)
					(thickness 0.15)
				)
				(justify mirror)
			)
		)
		(property "Author" "Antmicro"
			(at 0 0 180)
			(unlocked yes)
			(layer "B.Fab")
			(hide yes)
			(effects
				(font
					(size 1 1)
					(thickness 0.15)
				)
				(justify mirror)
			)
		)
		(property "Voltage" "25V"
			(at 0 0 180)
			(unlocked yes)
			(layer "B.Fab")
			(hide yes)
			(effects
				(font
					(size 1 1)
					(thickness 0.15)
				)
				(justify mirror)
			)
		)
		(property "Dielectric" "X5R"
			(at 0 0 180)
			(unlocked yes)
			(layer "B.Fab")
			(hide yes)
			(effects
				(font
					(size 1 1)
					(thickness 0.15)
				)
				(justify mirror)
			)
		)
		(property "Public" "False"
			(at 0 0 180)
			(unlocked yes)
			(layer "B.Fab")
			(hide yes)
			(effects
				(font
					(size 1 1)
					(thickness 0.15)
				)
				(justify mirror)
			)
		)
		(sheetname "/USB/")
		(sheetfile "usb.kicad_sch")
		(attr smd)
		(fp_line
			(start -0.3 0.7)
			(end 0.3 0.7)
			(stroke
				(width 0.15)
				(type solid)
			)
			(layer "B.SilkS")
		)
		(fp_line
			(start -0.3 -0.7)
			(end 0.3 -0.7)
			(stroke
				(width 0.15)
				(type solid)
			)
			(layer "B.SilkS")
		)
		(fp_rect
			(start 1.95 0.9)
			(end -1.95 -0.9)
			(stroke
				(width 0.05)
				(type default)
			)
			(fill no)
			(layer "B.CrtYd")
		)
		(fp_rect
			(start -0.95 0.675)
			(end 0.95 -0.675)
			(stroke
				(width 0.15)
				(type solid)
			)
			(fill no)
			(layer "B.Fab")
		)
		(fp_text user "Author: Antmicro"
			(at -1.9 -5.947 0)
			(layer "B.Fab")
			(effects
				(font
					(size 0.7 0.7)
					(thickness 0.15)
				)
				(justify left bottom mirror)
			)
		)
		(fp_text user "License: Apache-2.0"
			(at -1.9 -4.947 0)
			(layer "B.Fab")
			(effects
				(font
					(size 0.7 0.7)
					(thickness 0.15)
				)
				(justify left bottom mirror)
			)
		)
		(fp_text user "${REFERENCE}"
			(at -1.9 -3.947 0)
			(layer "B.Fab")
			(effects
				(font
					(size 0.7 0.7)
					(thickness 0.15)
				)
				(justify left bottom mirror)
			)
		)
		(pad "1" smd roundrect
			(at -1.1 0 180)
			(size 1.2 1.3)
			(layers "B.Cu" "B.Mask" "B.Paste")
			(roundrect_rratio 0.25)
			(net 113 "/USB/OUT_FTDI")
			(pintype "passive")
		)
		(pad "2" smd roundrect
			(at 1.1 0 180)
			(size 1.2 1.3)
			(layers "B.Cu" "B.Mask" "B.Paste")
			(roundrect_rratio 0.25)
			(net 3 "GND")
			(pintype "passive")
		)
	)
	(footprint "antmicro-footprints:R_0402_1005Metric"
		(layer "B.Cu")
		(at 80.817962 133.7915 180)
		(descr "Resistor SMD 0402")
		(tags "resistor SMD 0402")
		(property "Reference" "R908"
			(at -3.66 -0.445 0)
			(layer "B.SilkS")
			(effects
				(font
					(size 0.7 0.7)
					(thickness 0.15)
				)
				(justify left bottom mirror)
			)
		)
		(property "Value" "R_10k_0402"
			(at -1.011843 -1.772047 0)
			(layer "B.Fab")
			(effects
				(font
					(size 0.7 0.7)
					(thickness 0.15)
				)
				(justify left bottom mirror)
			)
		)
		(property "Datasheet" "https://www.bourns.com/docs/product-datasheets/cr.pdf"
			(at 0 0 180)
			(layer "B.Fab")
			(hide yes)
			(effects
				(font
					(size 1.27 1.27)
					(thickness 0.15)
				)
			)
		)
		(property "Manufacturer" "Bourns"
			(at 0 0 180)
			(unlocked yes)
			(layer "B.Fab")
			(hide yes)
			(effects
				(font
					(size 1 1)
					(thickness 0.15)
				)
				(justify mirror)
			)
		)
		(property "MPN" "CR0402-FX-1002GLF"
			(at 0 0 180)
			(unlocked yes)
			(layer "B.Fab")
			(hide yes)
			(effects
				(font
					(size 1 1)
					(thickness 0.15)
				)
				(justify mirror)
			)
		)
		(property "Val" "10k"
			(at 0 0 180)
			(unlocked yes)
			(layer "B.Fab")
			(hide yes)
			(effects
				(font
					(size 1 1)
					(thickness 0.15)
				)
				(justify mirror)
			)
		)
		(property "License" "Apache-2.0"
			(at 0 0 180)
			(unlocked yes)
			(layer "B.Fab")
			(hide yes)
			(effects
				(font
					(size 1 1)
					(thickness 0.15)
				)
				(justify mirror)
			)
		)
		(property "Author" "Antmicro"
			(at 0 0 180)
			(unlocked yes)
			(layer "B.Fab")
			(hide yes)
			(effects
				(font
					(size 1 1)
					(thickness 0.15)
				)
				(justify mirror)
			)
		)
		(property "Tolerance" "1%"
			(at 0 0 180)
			(unlocked yes)
			(layer "B.Fab")
			(hide yes)
			(effects
				(font
					(size 1 1)
					(thickness 0.15)
				)
				(justify mirror)
			)
		)
		(sheetname "/USB/")
		(sheetfile "usb.kicad_sch")
		(attr smd exclude_from_pos_files exclude_from_bom dnp)
		(fp_rect
			(start -0.925 0.47)
			(end 0.925 -0.47)
			(stroke
				(width 0.05)
				(type default)
			)
			(fill no)
			(layer "B.CrtYd")
		)
		(fp_rect
			(start -0.5 0.25)
			(end 0.5 -0.25)
			(stroke
				(width 0.15)
				(type solid)
			)
			(fill no)
			(layer "B.Fab")
		)
		(fp_text user "Author: Antmicro"
			(at -0.95 -4.169 0)
			(layer "B.Fab")
			(effects
				(font
					(size 0.7 0.7)
					(thickness 0.15)
				)
				(justify left bottom mirror)
			)
		)
		(fp_text user "${REFERENCE}"
			(at -0.95 -3.168 0)
			(layer "B.Fab")
			(effects
				(font
					(size 0.7 0.7)
					(thickness 0.15)
				)
				(justify left bottom mirror)
			)
		)
		(fp_text user "License: Apache-2.0"
			(at -0.95 -5.169 0)
			(layer "B.Fab")
			(effects
				(font
					(size 0.7 0.7)
					(thickness 0.15)
				)
				(justify left bottom mirror)
			)
		)
		(pad "1" smd roundrect
			(at -0.48 0 180)
			(size 0.59 0.64)
			(layers "B.Cu" "B.Mask" "B.Paste")
			(roundrect_rratio 0.25)
			(net 27 "/USB/USB_3V3")
			(pintype "passive")
		)
		(pad "2" smd roundrect
			(at 0.48 0 180)
			(size 0.59 0.64)
			(layers "B.Cu" "B.Mask" "B.Paste")
			(roundrect_rratio 0.25)
			(net 282 "/USB/EECLK")
			(pintype "passive")
		)
	)
)
